FILE_TYPE = CONNECTIVITY;
{Allegro Design Entry HDL 16.6-p007 (v16-6-112F) 10/10/2012}
"PAGE_NUMBER" = 173;
0"NC";
1"SATA6G_PCH_PCIE_UP_SATA_TXN<7:0>";
2"SATA6G_PCH_PCIE_UP_SATA_TXP<7:0>";
3"SATA6G_PCH_PCIE_UP_SATA_RXP<7:0>";
4"SATA6G_PCH_PCIE_UP_SATA_RXN<7:0>";
5"GND\g";
6"GND\g";
7"P3V3\g";
8"P3V3\g";
9"GND\g";
10"GND\g";
11"SATA6G_P3_RX_C_DN";
12"SATA6G_P7_TX_C_DN";
13"SATA6G_P0_TX_C_DN";
14"PD_SATA0_CONTROLLER_TYPE_R";
15"SATA6G_P2_TX_C_DP";
16"SATA6G_P1_TX_C_DP";
17"SATA6G_P6_RX_C_DP";
18"SATA6G_PCH_PCIE_UP_SATA_RXN<2>";
19"SATA6G_P6_RX_C_DN";
20"SATA6G_PCH_PCIE_UP_SATA_RXP<4>";
21"SATA6G_P7_RX_C_DN";
22"SATA6G_P7_RX_C_DP";
23"SATA6G_P7_TX_C_DP";
24"SATA6G_PCH_PCIE_UP_SATA_TXP<2>";
25"SATA6G_P1_TX_C_DN";
26"SATA6G_P0_TX_C_DP";
27"SATA6G_PCH_PCIE_UP_SATA_TXP<5>";
28"SATA6G_P5_TX_C_DP";
29"SATA6G_PCH_PCIE_UP_SATA_TXP<7>";
30"SATA6G_P5_TX_C_DN";
31"SATA6G_P6_TX_C_DN";
32"SATA6G_P3_TX_C_DN";
33"SATA6G_P3_TX_C_DP";
34"PD_SATA1_CONTROLLER_TYPE_R";
35"SATA6G_PCH_PCIE_UP_SATA_RXP<7>";
36"SATA6G_PCH_PCIE_UP_SATA_RXN<7>";
37"SATA6G_PCH_PCIE_UP_SATA_RXN<6>";
38"SATA6G_PCH_PCIE_UP_SATA_RXP<6>";
39"SATA6G_PCH_PCIE_UP_SATA_RXN<4>";
40"SATA6G_PCH_PCIE_UP_SATA_RXP<2>";
41"SATA6G_PCH_PCIE_UP_SATA_RXN<3>";
42"SATA6G_PCH_PCIE_UP_SATA_RXP<3>";
43"SATA6G_PCH_PCIE_UP_SATA_RXN<5>";
44"SATA6G_PCH_PCIE_UP_SATA_RXP<5>";
45"SATA6G_PCH_PCIE_UP_SATA_RXN<1>";
46"SATA6G_P4_RX_C_DN";
47"SATA6G_P3_RX_C_DP";
48"SATA6G_P2_RX_C_DN";
49"SATA6G_P2_RX_C_DP";
50"SATA6G_P1_RX_C_DN";
51"SATA6G_PCH_PCIE_UP_SATA_RXN<0>";
52"SATA6G_PCH_PCIE_UP_SATA_RXP<0>";
53"SATA6G_PCH_PCIE_UP_SATA_RXP<1>";
54"SATA6G_P1_RX_C_DP";
55"SATA6G_P4_RX_C_DP";
56"SATA6G_P5_RX_C_DP";
57"SATA6G_P5_RX_C_DN";
58"PU_DATAIN1_SATA_1_R";
59"TP_FM_QAT_CBL_PRSNT0_R_N";
60"TP_FM_QAT_CBL_PRSNT1_N_R";
61"TP_SGPIO_SATA_DATA1_R";
62"SGPIO_PCH_SATA_DOUT0_R";
63"TP_SGPIO_SATA_CLOCK1_R";
64"TP_SGPIO_SATA_LOAD1_R";
65"SGPIO_PCH_SATA_LOAD_R";
66"SGPIO_PCH_SATA_CLOCK_R";
67"SATA6G_P4_TX_C_DN";
68"PU_DATAIN1_SATA_0_R";
69"SATA6G_P0_RX_C_DN";
70"SATA6G_P0_RX_C_DP";
71"SATA6G_P6_TX_C_DP";
72"SATA6G_P4_TX_C_DP";
73"SATA6G_P2_TX_C_DN";
74"SATA6G_PCH_PCIE_UP_SATA_TXN<7>";
75"SATA6G_PCH_PCIE_UP_SATA_TXN<6>";
76"SATA6G_PCH_PCIE_UP_SATA_TXP<6>";
77"SATA6G_PCH_PCIE_UP_SATA_TXP<4>";
78"SATA6G_PCH_PCIE_UP_SATA_TXP<3>";
79"SATA6G_PCH_PCIE_UP_SATA_TXN<5>";
80"SATA6G_PCH_PCIE_UP_SATA_TXN<4>";
81"SATA6G_PCH_PCIE_UP_SATA_TXN<3>";
82"SATA6G_PCH_PCIE_UP_SATA_TXN<2>";
83"SATA6G_PCH_PCIE_UP_SATA_TXP<0>";
84"SATA6G_PCH_PCIE_UP_SATA_TXP<1>";
85"SATA6G_PCH_PCIE_UP_SATA_TXN<1>";
86"SATA6G_PCH_PCIE_UP_SATA_TXN<0>";
%"GND"
"1","(-1150,1425)","0","mstr_symbols","I103";
;
BODY_TYPE"PLUMBING"
CDS_LIB"mstr_symbols"
SIZE"1B"
BOM_COST"ST_SATA"
ROOM"ST_SATA"
HDL_POWER"GND"
VOLTAGE"0.0V";
"A\NAC"5;
%"GND"
"1","(-2925,1450)","0","mstr_symbols","I162";
;
BODY_TYPE"PLUMBING"
CDS_LIB"mstr_symbols"
BOM_COST"ST_SATA"
SIZE"1B"
ROOM"ST_SATA"
HDL_POWER"GND"
VOLTAGE"0.0V";
"A\NAC"6;
%"CONN72_G97614002_A"
"1","(-2025,3100)","0","mstr_conn","I163";
;
CDS_SEC"1"
BOM_COST"ST_SATA"
CDS_LIB"mstr_conn"
SEC_TYPE"CP"
SEC"1"
CDS_LOCATION"J8A1"
ROOM"ST_SATA"
PACK_TYPE"CP"
MATERIAL"CONN"
PART_NUMBER"G97614-002"
LOCATION"J8A1";
"GND<23>"
$PN"1A3"6;
"RXA0_DP"
$PN"1B4"70;
"RXA3_DN"
$PN"1A8"11;
"TXB0_DP"
$PN"2D4"72;
"RXB1_DN"
$PN"2A5"57;
"GND<11>"
$PN"2A3"6;
"GND<22>"
$PN"1A6"6;
"GND<21>"
$PN"1A9"6;
"GND<18>"
$PN"1B9"6;
"GND<17>"
$PN"1C3"5;
"GND<16>"
$PN"1C6"5;
"GND<15>"
$PN"1C9"5;
"GND<14>"
$PN"1D3"5;
"GND<13>"
$PN"1D6"5;
"GND<12>"
$PN"1D9"5;
"GND<9>"
$PN"2A9"6;
"GND<8>"
$PN"2B3"6;
"GND<7>"
$PN"2B6"6;
"GND<6>"
$PN"2B9"6;
"GND<5>"
$PN"2C3"5;
"GND<4>"
$PN"2C6"5;
"GND<3>"
$PN"2C9"5;
"GND<2>"
$PN"2D3"5;
"GND<1>"
$PN"2D6"5;
"GND<0>"
$PN"2D9"5;
"RXA0_DN"
$PN"1B5"69;
"RXA1_DN"
$PN"1A5"50;
"RXA1_DP"
$PN"1A4"54;
"RXA2_DN"
$PN"1B8"48;
"RXA3_DP"
$PN"1A7"47;
"RXB1_DP"
$PN"2A4"56;
"RXB2_DN"
$PN"2B8"19;
"RXB2_DP"
$PN"2B7"17;
"RXB3_DN"
$PN"2A8"21;
"RXB3_DP"
$PN"2A7"22;
"SIDEBANDA_0"
$PN"1A2"66;
"SIDEBANDA_1"
$PN"1B2"65;
"SIDEBANDA_2"
$PN"1C2"5;
"SIDEBANDA_5"
$PN"1D1"68;
"SIDEBANDA_6"
$PN"1D2"14;
"SIDEBANDB_3"
$PN"2B1"6;
"SIDEBANDB_4"
$PN"2C1"61;
"SIDEBANDB_5"
$PN"2D1"58;
"SIDEBANDB_7"
$PN"2A1"60;
"TXA0_DN"
$PN"1D5"13;
"TXA0_DP"
$PN"1D4"26;
"TXA1_DN"
$PN"1C5"25;
"TXA1_DP"
$PN"1C4"16;
"TXA2_DN"
$PN"1D8"73;
"TXA2_DP"
$PN"1D7"15;
"TXA3_DN"
$PN"1C8"32;
"TXA3_DP"
$PN"1C7"33;
"TXB0_DN"
$PN"2D5"67;
"TXB1_DN"
$PN"2C5"30;
"TXB1_DP"
$PN"2C4"28;
"TXB2_DN"
$PN"2D8"31;
"TXB2_DP"
$PN"2D7"71;
"TXB3_DN"
$PN"2C8"12;
"TXB3_DP"
$PN"2C7"23;
"GND<19>"
$PN"1B6"6;
"GND<10>"
$PN"2A6"6;
"SIDEBANDA_4"
$PN"1C1"62;
"RXB0_DN"
$PN"2B5"46;
"RXB0_DP"
$PN"2B4"55;
"GND<20>"
$PN"1B3"6;
"RXA2_DP"
$PN"1B7"49;
"SIDEBANDA_7"
$PN"1A1"59;
"SIDEBANDA_3"
$PN"1B1"6;
"SIDEBANDB_1"
$PN"2B2"64;
"SIDEBANDB_0"
$PN"2A2"63;
"SIDEBANDB_2"
$PN"2C2"5;
"SIDEBANDB_6"
$PN"2D2"34;
%"CAP_A"
"2","(-4900,3550)","0","dev_discrete","I165";
;
SEC"1"
SEC_TYPE"0402V"
CDS_SEC"1"
CDS_LIB"dev_discrete"
BOM_COST"ST_SATA"
CDS_LOCATION"C2L13"
ROOM"ST_SATA"
MATERIAL"X7R"
VOLTAGE"25V"
PACK_TYPE"0402V"
TOLERANCE"10%"
VALUE"0.01UF"
PART_NUMBER"A36096-045"
LOCATION"C2L13";
"A"
$PN"1"18;
"B"
$PN"2"48;
%"CAP_A"
"2","(-4850,4050)","0","dev_discrete","I166";
;
CDS_LOCATION"C2L6"
BOM_COST"ST_SATA"
CDS_LIB"dev_discrete"
CDS_SEC"1"
SEC_TYPE"0402V"
SEC"1"
ROOM"ST_SATA"
MATERIAL"X7R"
VOLTAGE"25V"
PACK_TYPE"0402V"
TOLERANCE"10%"
VALUE"0.01UF"
PART_NUMBER"A36096-045"
LOCATION"C2L6";
"A"
$PN"1"45;
"B"
$PN"2"50;
%"CAP_A"
"2","(-4575,4550)","0","dev_discrete","I172";
;
SEC"1"
SEC_TYPE"0402V"
CDS_SEC"1"
CDS_LIB"dev_discrete"
BOM_COST"ST_SATA"
CDS_LOCATION"C2L19"
ROOM"ST_SATA"
MATERIAL"X7R"
VOLTAGE"25V"
PACK_TYPE"0402V"
TOLERANCE"10%"
VALUE"0.01UF"
PART_NUMBER"A36096-045"
LOCATION"C2L19";
"A"
$PN"1"52;
"B"
$PN"2"70;
%"CAP_A"
"2","(-4575,4200)","0","dev_discrete","I173";
;
CDS_LOCATION"C2L10"
BOM_COST"ST_SATA"
CDS_LIB"dev_discrete"
CDS_SEC"1"
SEC_TYPE"0402V"
SEC"1"
ROOM"ST_SATA"
LOCATION"C2L10"
MATERIAL"X7R"
VOLTAGE"25V"
PACK_TYPE"0402V"
TOLERANCE"10%"
VALUE"0.01UF"
PART_NUMBER"A36096-045";
"A"
$PN"1"53;
"B"
$PN"2"54;
%"CAP_A"
"2","(-4850,4400)","0","dev_discrete","I174";
;
SEC"1"
SEC_TYPE"0402V"
CDS_SEC"1"
CDS_LIB"dev_discrete"
BOM_COST"ST_SATA"
CDS_LOCATION"C2L17"
ROOM"ST_SATA"
MATERIAL"X7R"
VOLTAGE"25V"
PACK_TYPE"0402V"
TOLERANCE"10%"
VALUE"0.01UF"
PART_NUMBER"A36096-045"
LOCATION"C2L17";
"A"
$PN"1"51;
"B"
$PN"2"69;
%"TAP"
"6","(-5250,4400)","0","mstr_standard","I175";
;
HDL_TAP"TRUE"
BODY_TYPE"PLUMBING"
CDS_LIB"mstr_standard";
"B \NAC \NWC"4;
"S \NAC"
BN"0"51;
%"TAP"
"6","(-5400,4550)","0","mstr_standard","I176";
;
HDL_TAP"TRUE"
BODY_TYPE"PLUMBING"
CDS_LIB"mstr_standard";
"B \NAC \NWC"3;
"S \NAC"
BN"0"52;
%"TAP"
"6","(-5400,4200)","0","mstr_standard","I177";
;
CDS_LIB"mstr_standard"
BODY_TYPE"PLUMBING"
HDL_TAP"TRUE";
"B \NAC \NWC"3;
"S \NAC"
BN"1"53;
%"CAP_A"
"2","(-4575,3700)","0","dev_discrete","I191";
;
SEC"1"
SEC_TYPE"0402V"
CDS_SEC"1"
CDS_LIB"dev_discrete"
BOM_COST"ST_SATA"
CDS_LOCATION"C2L15"
ROOM"ST_SATA"
PACK_TYPE"0402V"
MATERIAL"X7R"
VOLTAGE"25V"
TOLERANCE"10%"
VALUE"0.01UF"
PART_NUMBER"A36096-045"
LOCATION"C2L15";
"A"
$PN"1"40;
"B"
$PN"2"49;
%"CAP_A"
"2","(-4575,3350)","0","dev_discrete","I192";
;
CDS_LOCATION"C2L4"
BOM_COST"ST_SATA"
CDS_LIB"dev_discrete"
CDS_SEC"1"
SEC_TYPE"0402V"
SEC"1"
ROOM"ST_SATA"
VALUE"0.01UF"
MATERIAL"X7R"
VOLTAGE"25V"
PACK_TYPE"0402V"
TOLERANCE"10%"
PART_NUMBER"A36096-045"
LOCATION"C2L4";
"A"
$PN"1"42;
"B"
$PN"2"47;
%"CAP_A"
"2","(-4900,3200)","0","dev_discrete","I194";
;
SEC"1"
SEC_TYPE"0402V"
CDS_SEC"1"
CDS_LIB"dev_discrete"
BOM_COST"ST_SATA"
CDS_LOCATION"C2L3"
ROOM"ST_SATA"
MATERIAL"X7R"
VOLTAGE"25V"
PACK_TYPE"0402V"
TOLERANCE"10%"
VALUE"0.01UF"
PART_NUMBER"A36096-045"
LOCATION"C2L3";
"A"
$PN"1"41;
"B"
$PN"2"11;
%"CAP_A"
"2","(-4600,2900)","0","dev_discrete","I195";
;
SEC"1"
SEC_TYPE"0402V"
CDS_SEC"1"
CDS_LIB"dev_discrete"
BOM_COST"ST_SATA"
CDS_LOCATION"C2L20"
ROOM"ST_SATA"
MATERIAL"X7R"
VOLTAGE"25V"
PACK_TYPE"0402V"
TOLERANCE"10%"
VALUE"0.01UF"
PART_NUMBER"A36096-045"
LOCATION"C2L20";
"A"
$PN"1"20;
"B"
$PN"2"55;
%"CAP_A"
"2","(-4575,2550)","0","dev_discrete","I196";
;
CDS_LOCATION"C2L12"
BOM_COST"ST_SATA"
CDS_LIB"dev_discrete"
CDS_SEC"1"
SEC_TYPE"0402V"
SEC"1"
ROOM"ST_SATA"
LOCATION"C2L12"
PART_NUMBER"A36096-045"
VALUE"0.01UF"
MATERIAL"X7R"
VOLTAGE"25V"
PACK_TYPE"0402V"
TOLERANCE"10%";
"A"
$PN"1"44;
"B"
$PN"2"56;
%"CAP_A"
"2","(-4950,2750)","0","dev_discrete","I197";
;
SEC"1"
SEC_TYPE"0402V"
CDS_SEC"1"
CDS_LIB"dev_discrete"
BOM_COST"ST_SATA"
CDS_LOCATION"C2L18"
ROOM"ST_SATA"
LOCATION"C2L18"
PART_NUMBER"A36096-045"
MATERIAL"X7R"
VOLTAGE"25V"
PACK_TYPE"0402V"
TOLERANCE"10%"
VALUE"0.01UF";
"A"
$PN"1"39;
"B"
$PN"2"46;
%"TAP"
"6","(-5250,3550)","0","mstr_standard","I198";
;
HDL_TAP"TRUE"
BODY_TYPE"PLUMBING"
CDS_LIB"mstr_standard";
"B \NAC \NWC"4;
"S \NAC"
BN"2"18;
%"TAP"
"6","(-5400,3700)","0","mstr_standard","I199";
;
HDL_TAP"TRUE"
BODY_TYPE"PLUMBING"
CDS_LIB"mstr_standard";
"B \NAC \NWC"3;
"S \NAC"
BN"2"40;
%"TAP"
"6","(-5400,3350)","0","mstr_standard","I200";
;
CDS_LIB"mstr_standard"
BODY_TYPE"PLUMBING"
HDL_TAP"TRUE";
"B \NAC \NWC"3;
"S \NAC"
BN"3"42;
%"TAP"
"6","(-5250,3200)","0","mstr_standard","I201";
;
CDS_LIB"mstr_standard"
BODY_TYPE"PLUMBING"
HDL_TAP"TRUE";
"B \NAC \NWC"4;
"S \NAC"
BN"3"41;
%"TAP"
"6","(-5400,2900)","0","mstr_standard","I202";
;
HDL_TAP"TRUE"
BODY_TYPE"PLUMBING"
CDS_LIB"mstr_standard";
"B \NAC \NWC"3;
"S \NAC"
BN"4"20;
%"TAP"
"6","(-5400,2550)","0","mstr_standard","I203";
;
CDS_LIB"mstr_standard"
BODY_TYPE"PLUMBING"
HDL_TAP"TRUE";
"B \NAC \NWC"3;
"S \NAC"
BN"5"44;
%"TAP"
"6","(-5250,2750)","0","mstr_standard","I204";
;
HDL_TAP"TRUE"
BODY_TYPE"PLUMBING"
CDS_LIB"mstr_standard";
"B \NAC \NWC"4;
"S \NAC"
BN"4"39;
%"CAP_A"
"2","(-4575,2050)","0","dev_discrete","I205";
;
SEC"1"
SEC_TYPE"0402V"
CDS_SEC"1"
CDS_LIB"dev_discrete"
BOM_COST"ST_SATA"
CDS_LOCATION"C2L16"
ROOM"ST_SATA"
VALUE"0.01UF"
MATERIAL"X7R"
VOLTAGE"25V"
PACK_TYPE"0402V"
TOLERANCE"10%"
PART_NUMBER"A36096-045"
LOCATION"C2L16";
"A"
$PN"1"38;
"B"
$PN"2"17;
%"CAP_A"
"2","(-4575,1700)","0","dev_discrete","I206";
;
CDS_LOCATION"C2L7"
BOM_COST"ST_SATA"
CDS_LIB"dev_discrete"
CDS_SEC"1"
SEC_TYPE"0402V"
SEC"1"
ROOM"ST_SATA"
PACK_TYPE"0402V"
MATERIAL"X7R"
VOLTAGE"25V"
TOLERANCE"10%"
VALUE"0.01UF"
PART_NUMBER"A36096-045"
LOCATION"C2L7";
"A"
$PN"1"35;
"B"
$PN"2"22;
%"CAP_A"
"2","(-4950,2400)","0","dev_discrete","I207";
;
SEC"1"
SEC_TYPE"0402V"
CDS_SEC"1"
CDS_LIB"dev_discrete"
BOM_COST"ST_SATA"
CDS_LOCATION"C2L9"
ROOM"ST_SATA"
PART_NUMBER"A36096-045"
MATERIAL"X7R"
VOLTAGE"25V"
PACK_TYPE"0402V"
TOLERANCE"10%"
VALUE"0.01UF"
LOCATION"C2L9";
"A"
$PN"1"43;
"B"
$PN"2"57;
%"CAP_A"
"2","(-4975,1850)","0","dev_discrete","I208";
;
SEC"1"
SEC_TYPE"0402V"
CDS_SEC"1"
CDS_LIB"dev_discrete"
BOM_COST"ST_SATA"
CDS_LOCATION"C2L14"
ROOM"ST_SATA"
MATERIAL"X7R"
PACK_TYPE"0402V"
VOLTAGE"25V"
TOLERANCE"10%"
VALUE"0.01UF"
PART_NUMBER"A36096-045"
LOCATION"C2L14";
"A"
$PN"1"37;
"B"
$PN"2"19;
%"CAP_A"
"2","(-4975,1500)","0","dev_discrete","I209";
;
SEC"1"
SEC_TYPE"0402V"
CDS_SEC"1"
CDS_LIB"dev_discrete"
BOM_COST"ST_SATA"
CDS_LOCATION"C2L5"
ROOM"ST_SATA"
LOCATION"C2L5"
PART_NUMBER"A36096-045"
MATERIAL"X7R"
VOLTAGE"25V"
PACK_TYPE"0402V"
TOLERANCE"10%"
VALUE"0.01UF";
"A"
$PN"1"36;
"B"
$PN"2"21;
%"TAP"
"6","(-5250,2400)","0","mstr_standard","I210";
;
HDL_TAP"TRUE"
BODY_TYPE"PLUMBING"
CDS_LIB"mstr_standard";
"B \NAC \NWC"4;
"S \NAC"
BN"5"43;
%"TAP"
"6","(-5400,2050)","0","mstr_standard","I211";
;
HDL_TAP"TRUE"
BODY_TYPE"PLUMBING"
CDS_LIB"mstr_standard";
"B \NAC \NWC"3;
"S \NAC"
BN"6"38;
%"TAP"
"6","(-5400,1700)","0","mstr_standard","I212";
;
CDS_LIB"mstr_standard"
BODY_TYPE"PLUMBING"
HDL_TAP"TRUE";
"B \NAC \NWC"3;
"S \NAC"
BN"7"35;
%"TAP"
"6","(-5250,1850)","0","mstr_standard","I213";
;
HDL_TAP"TRUE"
BODY_TYPE"PLUMBING"
CDS_LIB"mstr_standard";
"B \NAC \NWC"4;
"S \NAC"
BN"6"37;
%"TAP"
"6","(-5250,1500)","0","mstr_standard","I214";
;
HDL_TAP"TRUE"
BODY_TYPE"PLUMBING"
CDS_LIB"mstr_standard";
"B \NAC \NWC"4;
"S \NAC"
BN"7"36;
%"TAP"
"1","(1300,1550)","0","mstr_standard","I215";
;
HDL_TAP"TRUE"
BODY_TYPE"PLUMBING"
CDS_LIB"mstr_standard";
"B \NAC \NWC"1;
"S \NAC"
BN"7"74;
%"TAP"
"1","(1450,4675)","0","mstr_standard","I216";
;
HDL_TAP"TRUE"
BODY_TYPE"PLUMBING"
CDS_LIB"mstr_standard";
"B \NAC \NWC"2;
"S \NAC"
BN"0"83;
%"TAP"
"1","(1450,4325)","0","mstr_standard","I217";
;
HDL_TAP"TRUE"
BODY_TYPE"PLUMBING"
CDS_LIB"mstr_standard";
"B \NAC \NWC"2;
"S \NAC"
BN"1"84;
%"TAP"
"1","(1300,4175)","0","mstr_standard","I218";
;
CDS_LIB"mstr_standard"
BODY_TYPE"PLUMBING"
HDL_TAP"TRUE";
"B \NAC \NWC"1;
"S \NAC"
BN"1"85;
%"TAP"
"1","(1300,4525)","0","mstr_standard","I219";
;
HDL_TAP"TRUE"
BODY_TYPE"PLUMBING"
CDS_LIB"mstr_standard";
"B \NAC \NWC"1;
"S \NAC"
BN"0"86;
%"CAP_A"
"2","(1025,4525)","0","dev_discrete","I220";
;
SEC"1"
SEC_TYPE"0402V"
CDS_SEC"1"
CDS_LIB"dev_discrete"
BOM_COST"ST_SATA"
CDS_LOCATION"C2L40"
ROOM"ST_SATA"
MATERIAL"X7R"
VOLTAGE"25V"
PACK_TYPE"0402V"
TOLERANCE"10%"
VALUE"0.01UF"
PART_NUMBER"A36096-045"
LOCATION"C2L40";
"A"
$PN"1"13;
"B"
$PN"2"86;
%"CAP_A"
"2","(650,4675)","0","dev_discrete","I221";
;
SEC"1"
SEC_TYPE"0402V"
CDS_SEC"1"
CDS_LIB"dev_discrete"
BOM_COST"ST_SATA"
CDS_LOCATION"C2L39"
ROOM"ST_SATA"
PACK_TYPE"0402V"
VALUE"0.01UF"
PART_NUMBER"A36096-045"
MATERIAL"X7R"
VOLTAGE"25V"
TOLERANCE"10%"
LOCATION"C2L39";
"A"
$PN"1"26;
"B"
$PN"2"83;
%"CAP_A"
"2","(650,4325)","0","dev_discrete","I222";
;
SEC"1"
SEC_TYPE"0402V"
CDS_SEC"1"
CDS_LIB"dev_discrete"
BOM_COST"ST_SATA"
CDS_LOCATION"C2L43"
ROOM"ST_SATA"
LOCATION"C2L43"
PART_NUMBER"A36096-045"
VALUE"0.01UF"
VOLTAGE"25V"
MATERIAL"X7R"
PACK_TYPE"0402V"
TOLERANCE"10%";
"A"
$PN"1"16;
"B"
$PN"2"84;
%"CAP_A"
"2","(1025,4175)","0","dev_discrete","I228";
;
CDS_LOCATION"C2L44"
BOM_COST"ST_SATA"
CDS_LIB"dev_discrete"
CDS_SEC"1"
SEC_TYPE"0402V"
SEC"1"
ROOM"ST_SATA"
MATERIAL"X7R"
VOLTAGE"25V"
PACK_TYPE"0402V"
TOLERANCE"10%"
VALUE"0.01UF"
PART_NUMBER"A36096-045"
LOCATION"C2L44";
"A"
$PN"1"25;
"B"
$PN"2"85;
%"TAP"
"1","(1450,3650)","0","mstr_standard","I229";
;
CDS_LIB"mstr_standard"
BODY_TYPE"PLUMBING"
HDL_TAP"TRUE";
"B \NAC \NWC"2;
"S \NAC"
BN"2"24;
%"TAP"
"1","(1450,3300)","0","mstr_standard","I230";
;
CDS_LIB"mstr_standard"
BODY_TYPE"PLUMBING"
HDL_TAP"TRUE";
"B \NAC \NWC"2;
"S \NAC"
BN"3"78;
%"TAP"
"1","(1300,3500)","0","mstr_standard","I231";
;
CDS_LIB"mstr_standard"
BODY_TYPE"PLUMBING"
HDL_TAP"TRUE";
"B \NAC \NWC"1;
"S \NAC"
BN"2"82;
%"TAP"
"1","(1300,3075)","0","mstr_standard","I232";
;
CDS_LIB"mstr_standard"
BODY_TYPE"PLUMBING"
HDL_TAP"TRUE";
"B \NAC \NWC"1;
"S \NAC"
BN"3"81;
%"CAP_A"
"2","(1000,3500)","0","dev_discrete","I233";
;
SEC"1"
SEC_TYPE"0402V"
CDS_SEC"1"
CDS_LIB"dev_discrete"
BOM_COST"ST_SATA"
CDS_LOCATION"C2L42"
ROOM"ST_SATA"
PART_NUMBER"A36096-045"
MATERIAL"X7R"
VOLTAGE"25V"
PACK_TYPE"0402V"
TOLERANCE"10%"
VALUE"0.01UF"
LOCATION"C2L42";
"A"
$PN"1"73;
"B"
$PN"2"82;
%"CAP_A"
"2","(1025,3075)","0","dev_discrete","I234";
;
SEC"1"
SEC_TYPE"0402V"
CDS_SEC"1"
CDS_LIB"dev_discrete"
BOM_COST"ST_SATA"
CDS_LOCATION"C2L22"
ROOM"ST_SATA"
MATERIAL"X7R"
VOLTAGE"25V"
PACK_TYPE"0402V"
TOLERANCE"10%"
VALUE"0.01UF"
PART_NUMBER"A36096-045"
LOCATION"C2L22";
"A"
$PN"1"32;
"B"
$PN"2"81;
%"TAP"
"1","(1450,2925)","0","mstr_standard","I235";
;
CDS_LIB"mstr_standard"
BODY_TYPE"PLUMBING"
HDL_TAP"TRUE";
"B \NAC \NWC"2;
"S \NAC"
BN"4"77;
%"TAP"
"1","(1450,2500)","0","mstr_standard","I236";
;
CDS_LIB"mstr_standard"
BODY_TYPE"PLUMBING"
HDL_TAP"TRUE";
"B \NAC \NWC"2;
"S \NAC"
BN"5"27;
%"TAP"
"1","(1300,2725)","0","mstr_standard","I237";
;
HDL_TAP"TRUE"
BODY_TYPE"PLUMBING"
CDS_LIB"mstr_standard";
"B \NAC \NWC"1;
"S \NAC"
BN"4"80;
%"CAP_A"
"2","(1025,2725)","0","dev_discrete","I238";
;
SEC"1"
SEC_TYPE"0402V"
CDS_SEC"1"
CDS_LIB"dev_discrete"
BOM_COST"ST_SATA"
CDS_LOCATION"C2L37"
ROOM"ST_SATA"
MATERIAL"X7R"
VOLTAGE"25V"
PACK_TYPE"0402V"
TOLERANCE"10%"
VALUE"0.01UF"
PART_NUMBER"A36096-045"
LOCATION"C2L37";
"A"
$PN"1"67;
"B"
$PN"2"80;
%"CAP_A"
"2","(650,2925)","0","dev_discrete","I239";
;
CDS_LOCATION"C2L47"
BOM_COST"ST_SATA"
CDS_LIB"dev_discrete"
CDS_SEC"1"
SEC_TYPE"0402V"
SEC"1"
ROOM"ST_SATA"
MATERIAL"X7R"
VOLTAGE"25V"
PACK_TYPE"0402V"
TOLERANCE"10%"
VALUE"0.01UF"
PART_NUMBER"A36096-045"
LOCATION"C2L47";
"A"
$PN"1"72;
"B"
$PN"2"77;
%"CAP_A"
"2","(650,2500)","0","dev_discrete","I240";
;
SEC"1"
SEC_TYPE"0402V"
CDS_SEC"1"
CDS_LIB"dev_discrete"
BOM_COST"ST_SATA"
CDS_LOCATION"C2L27"
ROOM"ST_SATA"
PART_NUMBER"A36096-045"
VALUE"0.01UF"
VOLTAGE"25V"
MATERIAL"X7R"
PACK_TYPE"0402V"
TOLERANCE"10%"
LOCATION"C2L27";
"A"
$PN"1"28;
"B"
$PN"2"27;
%"CAP_A"
"2","(625,3300)","0","dev_discrete","I241";
;
SEC"1"
SEC_TYPE"0402V"
CDS_SEC"1"
CDS_LIB"dev_discrete"
BOM_COST"ST_SATA"
CDS_LOCATION"C2L23"
ROOM"ST_SATA"
MATERIAL"X7R"
VOLTAGE"25V"
PACK_TYPE"0402V"
TOLERANCE"10%"
VALUE"0.01UF"
PART_NUMBER"A36096-045"
LOCATION"C2L23";
"A"
$PN"1"33;
"B"
$PN"2"78;
%"CAP_A"
"2","(625,3650)","0","dev_discrete","I242";
;
CDS_LOCATION"C2L41"
BOM_COST"ST_SATA"
CDS_LIB"dev_discrete"
CDS_SEC"1"
SEC_TYPE"0402V"
SEC"1"
ROOM"ST_SATA"
PART_NUMBER"A36096-045"
VOLTAGE"25V"
MATERIAL"X7R"
PACK_TYPE"0402V"
TOLERANCE"10%"
VALUE"0.01UF"
LOCATION"C2L41";
"A"
$PN"1"15;
"B"
$PN"2"24;
%"TAP"
"1","(1300,2350)","0","mstr_standard","I251";
;
HDL_TAP"TRUE"
BODY_TYPE"PLUMBING"
CDS_LIB"mstr_standard";
"B \NAC \NWC"1;
"S \NAC"
BN"5"79;
%"TAP"
"1","(1450,2050)","0","mstr_standard","I252";
;
HDL_TAP"TRUE"
BODY_TYPE"PLUMBING"
CDS_LIB"mstr_standard";
"B \NAC \NWC"2;
"S \NAC"
BN"6"76;
%"TAP"
"1","(1450,1700)","0","mstr_standard","I253";
;
CDS_LIB"mstr_standard"
BODY_TYPE"PLUMBING"
HDL_TAP"TRUE";
"B \NAC \NWC"2;
"S \NAC"
BN"7"29;
%"TAP"
"1","(1300,1900)","0","mstr_standard","I254";
;
HDL_TAP"TRUE"
BODY_TYPE"PLUMBING"
CDS_LIB"mstr_standard";
"B \NAC \NWC"1;
"S \NAC"
BN"6"75;
%"CAP_A"
"2","(1025,2350)","0","dev_discrete","I255";
;
SEC"1"
SEC_TYPE"0402V"
CDS_SEC"1"
CDS_LIB"dev_discrete"
BOM_COST"ST_SATA"
CDS_LOCATION"C2L26"
ROOM"ST_SATA"
MATERIAL"X7R"
VOLTAGE"25V"
PACK_TYPE"0402V"
TOLERANCE"10%"
VALUE"0.01UF"
PART_NUMBER"A36096-045"
LOCATION"C2L26";
"A"
$PN"1"30;
"B"
$PN"2"79;
%"CAP_A"
"2","(1050,1900)","0","dev_discrete","I256";
;
SEC"1"
SEC_TYPE"0402V"
CDS_SEC"1"
CDS_LIB"dev_discrete"
BOM_COST"ST_SATA"
CDS_LOCATION"C2L38"
ROOM"ST_SATA"
VALUE"0.01UF"
PART_NUMBER"A36096-045"
MATERIAL"X7R"
VOLTAGE"25V"
PACK_TYPE"0402V"
TOLERANCE"10%"
LOCATION"C2L38";
"A"
$PN"1"31;
"B"
$PN"2"75;
%"CAP_A"
"2","(650,2050)","0","dev_discrete","I257";
;
SEC"1"
SEC_TYPE"0402V"
CDS_SEC"1"
CDS_LIB"dev_discrete"
BOM_COST"ST_SATA"
CDS_LOCATION"C2L48"
ROOM"ST_SATA"
LOCATION"C2L48"
MATERIAL"X7R"
VOLTAGE"25V"
PACK_TYPE"0402V"
TOLERANCE"10%"
VALUE"0.01UF"
PART_NUMBER"A36096-045";
"A"
$PN"1"71;
"B"
$PN"2"76;
%"CAP_A"
"2","(650,1700)","0","dev_discrete","I258";
;
CDS_LOCATION"C2L24"
BOM_COST"ST_SATA"
CDS_LIB"dev_discrete"
CDS_SEC"1"
SEC_TYPE"0402V"
SEC"1"
ROOM"ST_SATA"
PART_NUMBER"A36096-045"
PACK_TYPE"0402V"
LOCATION"C2L24"
MATERIAL"X7R"
VOLTAGE"25V"
TOLERANCE"10%"
VALUE"0.01UF";
"A"
$PN"1"23;
"B"
$PN"2"29;
%"CAP_A"
"2","(1050,1550)","0","dev_discrete","I259";
;
SEC"1"
SEC_TYPE"0402V"
CDS_SEC"1"
CDS_LIB"dev_discrete"
BOM_COST"ST_SATA"
CDS_LOCATION"C2L21"
ROOM"ST_SATA"
VALUE"0.01UF"
MATERIAL"X7R"
VOLTAGE"25V"
PACK_TYPE"0402V"
TOLERANCE"10%"
PART_NUMBER"A36096-045"
LOCATION"C2L21";
"A"
$PN"1"12;
"B"
$PN"2"74;
%"P3V3"
"1","(-4075,2300)","0","mstr_symbols","I260";
;
SIZE"1B"
BOM_COST"ST_SATA"
CDS_LIB"mstr_symbols"
BODY_TYPE"PLUMBING"
ROOM"ST_SATA"
HDL_POWER"P3V3"
VOLTAGE"3.3V";
"G\NAC"7;
%"RES"
"1","(-3900,2200)","0","mstr_discrete","I261";
;
CDS_SEC"1"
CDS_LOCATION"R2L23"
SEC"1"
BOM_COST"ST_SATA"
CDS_LIB"mstr_discrete"
SEC_TYPE"0402"
ROOM"ST_SATA"
WATTAGE"1/16W"
MATERIAL"CHIP"
PACK_TYPE"0402"
TOLERANCE"1%"
VALUE"2.0K"
PART_NUMBER"G21796-001"
LOCATION"R2L23";
"B"
$PN"2"58;
"A"
$PN"1"7;
%"P3V3"
"1","(-3900,5025)","0","mstr_symbols","I262";
;
BODY_TYPE"PLUMBING"
SIZE"1B"
BOM_COST"ST_SATA"
CDS_LIB"mstr_symbols"
ROOM"ST_SATA"
HDL_POWER"P3V3"
VOLTAGE"3.3V";
"G\NAC"8;
%"RES"
"2","(-3900,4675)","0","mstr_discrete","I263";
;
CDS_SEC"1"
CDS_LOCATION"R2L21"
SEC"1"
BOM_COST"ST_SATA"
CDS_LIB"mstr_discrete"
SEC_TYPE"0402"
ROOM"ST_SATA"
WATTAGE"1/16W"
MATERIAL"CHIP"
PACK_TYPE"0402"
TOLERANCE"1%"
VALUE"2.0K"
PART_NUMBER"G21796-001"
LOCATION"R2L21";
"A"
$PN"1"8;
"B"
$PN"2"68;
%"RES"
"2","(1625,2000)","0","mstr_discrete","I264";
;
CDS_SEC"1"
CDS_LOCATION"R2L22"
SEC"1"
CDS_LIB"mstr_discrete"
BOM_COST"ST_SATA"
SEC_TYPE"0402"
ROOM"ST_SATA"
WATTAGE"1/16W"
MATERIAL"CHIP"
PACK_TYPE"0402"
TOLERANCE"1%"
VALUE"1.00K"
PART_NUMBER"G21796-026"
LOCATION"R2L22";
"A"
$PN"1"34;
"B"
$PN"2"9;
%"GND"
"1","(1625,1700)","0","mstr_symbols","I265";
;
BODY_TYPE"PLUMBING"
CDS_LIB"mstr_symbols"
SIZE"1B"
BOM_COST"ST_SATA"
ROOM"ST_SATA"
HDL_POWER"GND"
VOLTAGE"0.0V";
"A\NAC"9;
%"RES"
"2","(1675,3500)","0","mstr_discrete","I266";
;
CDS_SEC"1"
CDS_LOCATION"R2L18"
SEC"1"
BOM_COST"ST_SATA"
CDS_LIB"mstr_discrete"
SEC_TYPE"0402"
ROOM"ST_SATA"
WATTAGE"1/16W"
MATERIAL"CHIP"
PACK_TYPE"0402"
TOLERANCE"1%"
VALUE"1.00K"
PART_NUMBER"G21796-026"
LOCATION"R2L18";
"A"
$PN"1"14;
"B"
$PN"2"10;
%"GND"
"1","(1675,3275)","0","mstr_symbols","I267";
;
SIZE"1B"
BOM_COST"ST_SATA"
CDS_LIB"mstr_symbols"
BODY_TYPE"PLUMBING"
ROOM"ST_SATA"
HDL_POWER"GND"
VOLTAGE"0.0V";
"A\NAC"10;
%"TAP"
"6","(-5250,4050)","0","mstr_standard","I271";
;
HDL_TAP"TRUE"
BODY_TYPE"PLUMBING"
CDS_LIB"mstr_standard";
"B \NAC \NWC"4;
"S \NAC"
BN"1"45;
END.
